(kicad_pcb
	(version 20260206)
	(generator "pcbnew")
	(generator_version "10.0")
	(general
		(thickness 1.6)
		(legacy_teardrops no)
	)
	(paper "A4")
	(title_block
		(title "04192023_DAF0TMB3IC0_F0TG_MB_C_brd_V02_OCP.brd")
		(comment 1 "Grand Teton / footprints 7616-7624 of 8354")
	)
	(layers
		(0 "F.Cu" signal "TOP")
		(4 "In1.Cu" signal "GND")
		(6 "In2.Cu" signal "IN1")
		(8 "In3.Cu" signal "GND1")
		(10 "In4.Cu" signal "IN2")
		(12 "In5.Cu" signal "GND2")
		(14 "In6.Cu" signal "IN3")
		(16 "In7.Cu" signal "GND3")
		(18 "In8.Cu" signal "VCC")
		(20 "In9.Cu" signal "VCC1")
		(22 "In10.Cu" signal "GND4")
		(24 "In11.Cu" signal "IN4")
		(26 "In12.Cu" signal "GND5")
		(28 "In13.Cu" signal "IN5")
		(30 "In14.Cu" signal "GND6")
		(32 "In15.Cu" signal "IN6")
		(34 "In16.Cu" signal "GND7")
		(2 "B.Cu" signal "BOTTOM")
		(9 "F.Adhes" user "F.Adhesive")
		(11 "B.Adhes" user "B.Adhesive")
		(13 "F.Paste" user "Package Geometry/Pastemask Top")
		(15 "B.Paste" user "Package Geometry/Pastemask Bottom")
		(5 "F.SilkS" user "Ref Des/Silkscreen Top")
		(7 "B.SilkS" user "Ref Des/Silkscreen Bottom")
		(1 "F.Mask" user "Board Geometry/Soldermask Top")
		(3 "B.Mask" user "Board Geometry/Soldermask Bottom")
		(17 "Dwgs.User" user "User.Drawings")
		(19 "Cmts.User" user "User.Comments")
		(21 "Eco1.User" user "User.Eco1")
		(23 "Eco2.User" user "User.Eco2")
		(25 "Edge.Cuts" user "Board Geometry/Outline")
		(27 "Margin" user)
		(31 "F.CrtYd" user "Package Geometry/Place Bound Top")
		(29 "B.CrtYd" user "Package Geometry/Place Bound Bottom")
		(35 "F.Fab" user "Ref Des/Assembly Top")
		(33 "B.Fab" user "Ref Des/Assembly Bottom")
	)
	(footprint ""
		(layer "B.Cu")
		(at 287.149286 -428.26051)
		(property "Reference" "R2666"
			(at 0 0 0)
			(layer "B.SilkS")
			(hide yes)
			(effects
				(font
					(size 1.27 1.27)
				)
				(justify mirror)
			)
		)
		(property "Value" ""
			(at 0 0 0)
			(layer "B.Fab")
			(effects
				(font
					(size 1.27 1.27)
				)
				(justify mirror)
			)
		)
		(duplicate_pad_numbers_are_jumpers no)
		(fp_line
			(start -0.7874 -0.4064)
			(end -0.7874 0.4064)
			(stroke
				(width 0.1524)
				(type default)
			)
			(layer "B.SilkS")
		)
		(fp_line
			(start -0.7874 0.4064)
			(end 0.7874 0.4064)
			(stroke
				(width 0.1524)
				(type default)
			)
			(layer "B.SilkS")
		)
		(fp_line
			(start 0.7874 -0.4064)
			(end -0.7874 -0.4064)
			(stroke
				(width 0.1524)
				(type default)
			)
			(layer "B.SilkS")
		)
		(fp_line
			(start 0.7874 0.4064)
			(end 0.7874 -0.4064)
			(stroke
				(width 0.1524)
				(type default)
			)
			(layer "B.SilkS")
		)
		(fp_line
			(start -0.67945 -0.3048)
			(end -0.67945 0.3048)
			(stroke
				(width 0.1)
				(type default)
			)
			(layer "B.Fab")
		)
		(fp_line
			(start -0.67945 0.3048)
			(end -0.120396 0.3048)
			(stroke
				(width 0.1)
				(type default)
			)
			(layer "B.Fab")
		)
		(fp_line
			(start -0.12065 -0.3048)
			(end -0.67945 -0.3048)
			(stroke
				(width 0.1)
				(type default)
			)
			(layer "B.Fab")
		)
		(fp_line
			(start -0.12065 -0.2794)
			(end -0.12065 -0.3048)
			(stroke
				(width 0.1)
				(type default)
			)
			(layer "B.Fab")
		)
		(fp_line
			(start -0.120396 0.2794)
			(end 0.12065 0.2794)
			(stroke
				(width 0.1)
				(type default)
			)
			(layer "B.Fab")
		)
		(fp_line
			(start -0.120396 0.3048)
			(end -0.120396 0.2794)
			(stroke
				(width 0.1)
				(type default)
			)
			(layer "B.Fab")
		)
		(fp_line
			(start 0.12065 -0.305054)
			(end 0.12065 -0.2794)
			(stroke
				(width 0.1)
				(type default)
			)
			(layer "B.Fab")
		)
		(fp_line
			(start 0.12065 -0.2794)
			(end -0.12065 -0.2794)
			(stroke
				(width 0.1)
				(type default)
			)
			(layer "B.Fab")
		)
		(fp_line
			(start 0.12065 0.2794)
			(end 0.12065 0.3048)
			(stroke
				(width 0.1)
				(type default)
			)
			(layer "B.Fab")
		)
		(fp_line
			(start 0.12065 0.3048)
			(end 0.67945 0.3048)
			(stroke
				(width 0.1)
				(type default)
			)
			(layer "B.Fab")
		)
		(fp_line
			(start 0.67945 -0.305054)
			(end 0.12065 -0.305054)
			(stroke
				(width 0.1)
				(type default)
			)
			(layer "B.Fab")
		)
		(fp_line
			(start 0.67945 0.3048)
			(end 0.67945 -0.305054)
			(stroke
				(width 0.1)
				(type default)
			)
			(layer "B.Fab")
		)
		(pad "1" smd circle
			(at 0.40005 0 180)
			(size 0 0)
			(layers "B.Cu" "B.Mask" "B.Paste")
			(net "SMB_BMC_SWB_EN")
		)
		(pad "2" smd circle
			(at -0.40005 0 180)
			(size 0 0)
			(layers "B.Cu" "B.Mask" "B.Paste")
			(net "GND")
		)
	)
	(footprint ""
		(layer "B.Cu")
		(at 165.08984 -384.29946 -90)
		(property "Reference" "C426"
			(at 0 0 90)
			(layer "B.SilkS")
			(hide yes)
			(effects
				(font
					(size 1.27 1.27)
				)
				(justify mirror)
			)
		)
		(property "Value" ""
			(at 0 0 90)
			(layer "B.Fab")
			(effects
				(font
					(size 1.27 1.27)
				)
				(justify mirror)
			)
		)
		(duplicate_pad_numbers_are_jumpers no)
		(fp_line
			(start -0.299974 0.150114)
			(end 0.299974 0.150114)
			(stroke
				(width 0.1)
				(type default)
			)
			(layer "B.Fab")
		)
		(fp_line
			(start 0.299974 0.150114)
			(end 0.299974 -0.150114)
			(stroke
				(width 0.1)
				(type default)
			)
			(layer "B.Fab")
		)
		(fp_line
			(start -0.299974 -0.150114)
			(end -0.299974 0.150114)
			(stroke
				(width 0.1)
				(type default)
			)
			(layer "B.Fab")
		)
		(fp_line
			(start 0.299974 -0.150114)
			(end -0.299974 -0.150114)
			(stroke
				(width 0.1)
				(type default)
			)
			(layer "B.Fab")
		)
		(pad "1" smd rect
			(at 0.2667 0 90)
			(size 0.3048 0.381)
			(layers "B.Cu" "B.Mask" "B.Paste")
			(net "P0V9_CPU1_RT2_2A")
		)
		(pad "2" smd rect
			(at -0.2667 0 90)
			(size 0.3048 0.381)
			(layers "B.Cu" "B.Mask" "B.Paste")
			(net "GND")
		)
	)
	(footprint ""
		(layer "B.Cu")
		(at 91.392502 -207.41005 90)
		(property "Reference" "R618"
			(at 0 0 90)
			(layer "B.SilkS")
			(hide yes)
			(effects
				(font
					(size 1.27 1.27)
				)
				(justify mirror)
			)
		)
		(property "Value" ""
			(at 0 0 90)
			(layer "B.Fab")
			(effects
				(font
					(size 1.27 1.27)
				)
				(justify mirror)
			)
		)
		(duplicate_pad_numbers_are_jumpers no)
		(fp_line
			(start 0.7874 -0.4064)
			(end -0.7874 -0.4064)
			(stroke
				(width 0.1524)
				(type default)
			)
			(layer "B.SilkS")
		)
		(fp_line
			(start -0.7874 -0.4064)
			(end -0.7874 0.4064)
			(stroke
				(width 0.1524)
				(type default)
			)
			(layer "B.SilkS")
		)
		(fp_line
			(start 0.7874 0.4064)
			(end 0.7874 -0.4064)
			(stroke
				(width 0.1524)
				(type default)
			)
			(layer "B.SilkS")
		)
		(fp_line
			(start -0.7874 0.4064)
			(end 0.7874 0.4064)
			(stroke
				(width 0.1524)
				(type default)
			)
			(layer "B.SilkS")
		)
		(fp_line
			(start 0.67945 -0.305054)
			(end 0.12065 -0.305054)
			(stroke
				(width 0.1)
				(type default)
			)
			(layer "B.Fab")
		)
		(fp_line
			(start 0.12065 -0.305054)
			(end 0.12065 -0.2794)
			(stroke
				(width 0.1)
				(type default)
			)
			(layer "B.Fab")
		)
		(fp_line
			(start -0.12065 -0.3048)
			(end -0.67945 -0.3048)
			(stroke
				(width 0.1)
				(type default)
			)
			(layer "B.Fab")
		)
		(fp_line
			(start -0.67945 -0.3048)
			(end -0.67945 0.3048)
			(stroke
				(width 0.1)
				(type default)
			)
			(layer "B.Fab")
		)
		(fp_line
			(start 0.12065 -0.2794)
			(end -0.12065 -0.2794)
			(stroke
				(width 0.1)
				(type default)
			)
			(layer "B.Fab")
		)
		(fp_line
			(start -0.12065 -0.2794)
			(end -0.12065 -0.3048)
			(stroke
				(width 0.1)
				(type default)
			)
			(layer "B.Fab")
		)
		(fp_line
			(start 0.12065 0.2794)
			(end 0.12065 0.3048)
			(stroke
				(width 0.1)
				(type default)
			)
			(layer "B.Fab")
		)
		(fp_line
			(start -0.120396 0.2794)
			(end 0.12065 0.2794)
			(stroke
				(width 0.1)
				(type default)
			)
			(layer "B.Fab")
		)
		(fp_line
			(start 0.67945 0.3048)
			(end 0.67945 -0.305054)
			(stroke
				(width 0.1)
				(type default)
			)
			(layer "B.Fab")
		)
		(fp_line
			(start 0.12065 0.3048)
			(end 0.67945 0.3048)
			(stroke
				(width 0.1)
				(type default)
			)
			(layer "B.Fab")
		)
		(fp_line
			(start -0.120396 0.3048)
			(end -0.120396 0.2794)
			(stroke
				(width 0.1)
				(type default)
			)
			(layer "B.Fab")
		)
		(fp_line
			(start -0.67945 0.3048)
			(end -0.120396 0.3048)
			(stroke
				(width 0.1)
				(type default)
			)
			(layer "B.Fab")
		)
		(pad "1" smd circle
			(at 0.40005 0 270)
			(size 0 0)
			(layers "B.Cu" "B.Mask" "B.Paste")
			(net "CPU1_XTRIG_R2_L5")
		)
		(pad "2" smd circle
			(at -0.40005 0 270)
			(size 0 0)
			(layers "B.Cu" "B.Mask" "B.Paste")
			(net "CPU1_XTRIG_L5")
		)
	)
	(footprint ""
		(layer "B.Cu")
		(at 149.406356 -386.766562 90)
		(property "Reference" "C415"
			(at 0 0 90)
			(layer "B.SilkS")
			(hide yes)
			(effects
				(font
					(size 1.27 1.27)
				)
				(justify mirror)
			)
		)
		(property "Value" ""
			(at 0 0 90)
			(layer "B.Fab")
			(effects
				(font
					(size 1.27 1.27)
				)
				(justify mirror)
			)
		)
		(duplicate_pad_numbers_are_jumpers no)
		(fp_line
			(start 0.299974 -0.150114)
			(end -0.299974 -0.150114)
			(stroke
				(width 0.1)
				(type default)
			)
			(layer "B.Fab")
		)
		(fp_line
			(start -0.299974 -0.150114)
			(end -0.299974 0.150114)
			(stroke
				(width 0.1)
				(type default)
			)
			(layer "B.Fab")
		)
		(fp_line
			(start 0.299974 0.150114)
			(end 0.299974 -0.150114)
			(stroke
				(width 0.1)
				(type default)
			)
			(layer "B.Fab")
		)
		(fp_line
			(start -0.299974 0.150114)
			(end 0.299974 0.150114)
			(stroke
				(width 0.1)
				(type default)
			)
			(layer "B.Fab")
		)
		(pad "1" smd rect
			(at 0.2667 0 270)
			(size 0.3048 0.381)
			(layers "B.Cu" "B.Mask" "B.Paste")
			(net "P0V9_CPU1_RT2_2A")
		)
		(pad "2" smd rect
			(at -0.2667 0 270)
			(size 0.3048 0.381)
			(layers "B.Cu" "B.Mask" "B.Paste")
			(net "GND")
		)
	)
	(footprint ""
		(layer "B.Cu")
		(at 130.07848 -386.766562 90)
		(property "Reference" "C492"
			(at 0 0 90)
			(layer "B.SilkS")
			(hide yes)
			(effects
				(font
					(size 1.27 1.27)
				)
				(justify mirror)
			)
		)
		(property "Value" ""
			(at 0 0 90)
			(layer "B.Fab")
			(effects
				(font
					(size 1.27 1.27)
				)
				(justify mirror)
			)
		)
		(duplicate_pad_numbers_are_jumpers no)
		(fp_line
			(start 0.299974 -0.150114)
			(end -0.299974 -0.150114)
			(stroke
				(width 0.1)
				(type default)
			)
			(layer "B.Fab")
		)
		(fp_line
			(start -0.299974 -0.150114)
			(end -0.299974 0.150114)
			(stroke
				(width 0.1)
				(type default)
			)
			(layer "B.Fab")
		)
		(fp_line
			(start 0.299974 0.150114)
			(end 0.299974 -0.150114)
			(stroke
				(width 0.1)
				(type default)
			)
			(layer "B.Fab")
		)
		(fp_line
			(start -0.299974 0.150114)
			(end 0.299974 0.150114)
			(stroke
				(width 0.1)
				(type default)
			)
			(layer "B.Fab")
		)
		(pad "1" smd rect
			(at 0.2667 0 270)
			(size 0.3048 0.381)
			(layers "B.Cu" "B.Mask" "B.Paste")
			(net "P0V9_CPU1_RT3_2A")
		)
		(pad "2" smd rect
			(at -0.2667 0 270)
			(size 0.3048 0.381)
			(layers "B.Cu" "B.Mask" "B.Paste")
			(net "GND")
		)
	)
	(footprint ""
		(layer "B.Cu")
		(at 105.454196 -27.800808 -90)
		(property "Reference" "L6003"
			(at 0 0 90)
			(layer "B.SilkS")
			(hide yes)
			(effects
				(font
					(size 1.27 1.27)
				)
				(justify mirror)
			)
		)
		(property "Value" ""
			(at 0 0 90)
			(layer "B.Fab")
			(effects
				(font
					(size 1.27 1.27)
				)
				(justify mirror)
			)
		)
		(duplicate_pad_numbers_are_jumpers no)
		(fp_line
			(start -1.63576 0.8128)
			(end 1.63576 0.8128)
			(stroke
				(width 0.1524)
				(type default)
			)
			(layer "B.SilkS")
		)
		(fp_line
			(start -1.63576 -0.8128)
			(end -1.63576 0.8128)
			(stroke
				(width 0.1524)
				(type default)
			)
			(layer "B.SilkS")
		)
		(fp_line
			(start 1.63576 -0.8128)
			(end 1.63576 0.8128)
			(stroke
				(width 0.1524)
				(type default)
			)
			(layer "B.SilkS")
		)
		(fp_line
			(start 1.63576 -0.8128)
			(end -1.63576 -0.8128)
			(stroke
				(width 0.1524)
				(type default)
			)
			(layer "B.SilkS")
		)
		(fp_line
			(start -1.560576 0.7366)
			(end -1.560576 -0.738632)
			(stroke
				(width 0.1)
				(type default)
			)
			(layer "B.Fab")
		)
		(fp_line
			(start -1.524 0.7366)
			(end -1.560576 0.7366)
			(stroke
				(width 0.1)
				(type default)
			)
			(layer "B.Fab")
		)
		(fp_line
			(start 1.524 0.7366)
			(end -1.524 0.7366)
			(stroke
				(width 0.1)
				(type default)
			)
			(layer "B.Fab")
		)
		(fp_line
			(start 1.56083 0.7366)
			(end 1.524 0.7366)
			(stroke
				(width 0.1)
				(type default)
			)
			(layer "B.Fab")
		)
		(fp_line
			(start -1.560576 -0.738632)
			(end 1.56083 -0.738632)
			(stroke
				(width 0.1)
				(type default)
			)
			(layer "B.Fab")
		)
		(fp_line
			(start 1.56083 -0.738632)
			(end 1.56083 0.7366)
			(stroke
				(width 0.1)
				(type default)
			)
			(layer "B.Fab")
		)
		(pad "1" smd rect
			(at 0.94996 0 270)
			(size 1.1176 1.3716)
			(layers "B.Cu" "B.Mask" "B.Paste")
			(net "P3V3_AUX")
		)
		(pad "2" smd rect
			(at -0.94996 0 270)
			(size 1.1176 1.3716)
			(layers "B.Cu" "B.Mask" "B.Paste")
			(net "P3V3_AUX_CPU0_USB2_AVDD33")
		)
	)
	(footprint ""
		(layer "B.Cu")
		(at 349.834454 -255.84531)
		(property "Reference" "C2560"
			(at 0 0 0)
			(layer "B.SilkS")
			(hide yes)
			(effects
				(font
					(size 1.27 1.27)
				)
				(justify mirror)
			)
		)
		(property "Value" ""
			(at 0 0 0)
			(layer "B.Fab")
			(effects
				(font
					(size 1.27 1.27)
				)
				(justify mirror)
			)
		)
		(duplicate_pad_numbers_are_jumpers no)
		(fp_line
			(start -0.7874 -0.4064)
			(end -0.7874 0.4064)
			(stroke
				(width 0.1524)
				(type default)
			)
			(layer "B.SilkS")
		)
		(fp_line
			(start -0.7874 0.4064)
			(end 0.7874 0.4064)
			(stroke
				(width 0.1524)
				(type default)
			)
			(layer "B.SilkS")
		)
		(fp_line
			(start 0.7874 -0.4064)
			(end -0.7874 -0.4064)
			(stroke
				(width 0.1524)
				(type default)
			)
			(layer "B.SilkS")
		)
		(fp_line
			(start 0.7874 0.4064)
			(end 0.7874 -0.4064)
			(stroke
				(width 0.1524)
				(type default)
			)
			(layer "B.SilkS")
		)
		(fp_line
			(start -0.67945 -0.3048)
			(end -0.67945 0.3048)
			(stroke
				(width 0.1)
				(type default)
			)
			(layer "B.Fab")
		)
		(fp_line
			(start -0.67945 0.3048)
			(end -0.120396 0.3048)
			(stroke
				(width 0.1)
				(type default)
			)
			(layer "B.Fab")
		)
		(fp_line
			(start -0.12065 -0.3048)
			(end -0.67945 -0.3048)
			(stroke
				(width 0.1)
				(type default)
			)
			(layer "B.Fab")
		)
		(fp_line
			(start -0.12065 -0.2794)
			(end -0.12065 -0.3048)
			(stroke
				(width 0.1)
				(type default)
			)
			(layer "B.Fab")
		)
		(fp_line
			(start -0.120396 0.2794)
			(end 0.12065 0.2794)
			(stroke
				(width 0.1)
				(type default)
			)
			(layer "B.Fab")
		)
		(fp_line
			(start -0.120396 0.3048)
			(end -0.120396 0.2794)
			(stroke
				(width 0.1)
				(type default)
			)
			(layer "B.Fab")
		)
		(fp_line
			(start 0.12065 -0.305054)
			(end 0.12065 -0.2794)
			(stroke
				(width 0.1)
				(type default)
			)
			(layer "B.Fab")
		)
		(fp_line
			(start 0.12065 -0.2794)
			(end -0.12065 -0.2794)
			(stroke
				(width 0.1)
				(type default)
			)
			(layer "B.Fab")
		)
		(fp_line
			(start 0.12065 0.2794)
			(end 0.12065 0.3048)
			(stroke
				(width 0.1)
				(type default)
			)
			(layer "B.Fab")
		)
		(fp_line
			(start 0.12065 0.3048)
			(end 0.67945 0.3048)
			(stroke
				(width 0.1)
				(type default)
			)
			(layer "B.Fab")
		)
		(fp_line
			(start 0.67945 -0.305054)
			(end 0.12065 -0.305054)
			(stroke
				(width 0.1)
				(type default)
			)
			(layer "B.Fab")
		)
		(fp_line
			(start 0.67945 0.3048)
			(end 0.67945 -0.305054)
			(stroke
				(width 0.1)
				(type default)
			)
			(layer "B.Fab")
		)
		(pad "1" smd circle
			(at 0.40005 0 180)
			(size 0 0)
			(layers "B.Cu" "B.Mask" "B.Paste")
			(net "PVDDCR_SOC_P0")
		)
		(pad "2" smd circle
			(at -0.40005 0 180)
			(size 0 0)
			(layers "B.Cu" "B.Mask" "B.Paste")
			(net "GND")
		)
	)
	(footprint ""
		(layer "B.Cu")
		(at 204.5843 -402.744432 -90)
		(property "Reference" "PR3911"
			(at 0 0 90)
			(layer "B.SilkS")
			(hide yes)
			(effects
				(font
					(size 1.27 1.27)
				)
				(justify mirror)
			)
		)
		(property "Value" ""
			(at 0 0 90)
			(layer "B.Fab")
			(effects
				(font
					(size 1.27 1.27)
				)
				(justify mirror)
			)
		)
		(duplicate_pad_numbers_are_jumpers no)
		(fp_line
			(start -0.7874 0.4064)
			(end 0.7874 0.4064)
			(stroke
				(width 0.1524)
				(type default)
			)
			(layer "B.SilkS")
		)
		(fp_line
			(start 0.7874 0.4064)
			(end 0.7874 -0.4064)
			(stroke
				(width 0.1524)
				(type default)
			)
			(layer "B.SilkS")
		)
		(fp_line
			(start -0.7874 -0.4064)
			(end -0.7874 0.4064)
			(stroke
				(width 0.1524)
				(type default)
			)
			(layer "B.SilkS")
		)
		(fp_line
			(start 0.7874 -0.4064)
			(end -0.7874 -0.4064)
			(stroke
				(width 0.1524)
				(type default)
			)
			(layer "B.SilkS")
		)
		(fp_line
			(start -0.67945 0.3048)
			(end -0.120396 0.3048)
			(stroke
				(width 0.1)
				(type default)
			)
			(layer "B.Fab")
		)
		(fp_line
			(start -0.120396 0.3048)
			(end -0.120396 0.2794)
			(stroke
				(width 0.1)
				(type default)
			)
			(layer "B.Fab")
		)
		(fp_line
			(start 0.12065 0.3048)
			(end 0.67945 0.3048)
			(stroke
				(width 0.1)
				(type default)
			)
			(layer "B.Fab")
		)
		(fp_line
			(start 0.67945 0.3048)
			(end 0.67945 -0.305054)
			(stroke
				(width 0.1)
				(type default)
			)
			(layer "B.Fab")
		)
		(fp_line
			(start -0.120396 0.2794)
			(end 0.12065 0.2794)
			(stroke
				(width 0.1)
				(type default)
			)
			(layer "B.Fab")
		)
		(fp_line
			(start 0.12065 0.2794)
			(end 0.12065 0.3048)
			(stroke
				(width 0.1)
				(type default)
			)
			(layer "B.Fab")
		)
		(fp_line
			(start -0.12065 -0.2794)
			(end -0.12065 -0.3048)
			(stroke
				(width 0.1)
				(type default)
			)
			(layer "B.Fab")
		)
		(fp_line
			(start 0.12065 -0.2794)
			(end -0.12065 -0.2794)
			(stroke
				(width 0.1)
				(type default)
			)
			(layer "B.Fab")
		)
		(fp_line
			(start -0.67945 -0.3048)
			(end -0.67945 0.3048)
			(stroke
				(width 0.1)
				(type default)
			)
			(layer "B.Fab")
		)
		(fp_line
			(start -0.12065 -0.3048)
			(end -0.67945 -0.3048)
			(stroke
				(width 0.1)
				(type default)
			)
			(layer "B.Fab")
		)
		(fp_line
			(start 0.12065 -0.305054)
			(end 0.12065 -0.2794)
			(stroke
				(width 0.1)
				(type default)
			)
			(layer "B.Fab")
		)
		(fp_line
			(start 0.67945 -0.305054)
			(end 0.12065 -0.305054)
			(stroke
				(width 0.1)
				(type default)
			)
			(layer "B.Fab")
		)
		(pad "1" smd circle
			(at 0.40005 0 90)
			(size 0 0)
			(layers "B.Cu" "B.Mask" "B.Paste")
			(net "HSC_VDD_R_2")
		)
		(pad "2" smd circle
			(at -0.40005 0 90)
			(size 0 0)
			(layers "B.Cu" "B.Mask" "B.Paste")
			(net "HSC_VDD")
		)
	)
	(footprint ""
		(layer "B.Cu")
		(at 114.618516 -388.011162 -90)
		(property "Reference" "C500"
			(at 0 0 90)
			(layer "B.SilkS")
			(hide yes)
			(effects
				(font
					(size 1.27 1.27)
				)
				(justify mirror)
			)
		)
		(property "Value" ""
			(at 0 0 90)
			(layer "B.Fab")
			(effects
				(font
					(size 1.27 1.27)
				)
				(justify mirror)
			)
		)
		(duplicate_pad_numbers_are_jumpers no)
		(fp_line
			(start -0.299974 0.150114)
			(end 0.299974 0.150114)
			(stroke
				(width 0.1)
				(type default)
			)
			(layer "B.Fab")
		)
		(fp_line
			(start 0.299974 0.150114)
			(end 0.299974 -0.150114)
			(stroke
				(width 0.1)
				(type default)
			)
			(layer "B.Fab")
		)
		(fp_line
			(start -0.299974 -0.150114)
			(end -0.299974 0.150114)
			(stroke
				(width 0.1)
				(type default)
			)
			(layer "B.Fab")
		)
		(fp_line
			(start 0.299974 -0.150114)
			(end -0.299974 -0.150114)
			(stroke
				(width 0.1)
				(type default)
			)
			(layer "B.Fab")
		)
		(pad "1" smd rect
			(at 0.2667 0 90)
			(size 0.3048 0.381)
			(layers "B.Cu" "B.Mask" "B.Paste")
			(net "P0V9_CPU1_RT3_2A")
		)
		(pad "2" smd rect
			(at -0.2667 0 90)
			(size 0.3048 0.381)
			(layers "B.Cu" "B.Mask" "B.Paste")
			(net "GND")
		)
	)
)
